(kicad_pcb
	(version 20260206)
	(generator "pcbnew")
	(generator_version "10.0")
	(general
		(thickness 1.6)
		(legacy_teardrops no)
	)
	(paper "A4")
	(title_block
		(title "pdpb — Lightning_PDPB_BRD.brd")
		(comment 1 "Lightning (Wiwynn / Facebook NVMe JBOF) / footprints 859-865 of 1140")
	)
	(layers
		(0 "F.Cu" signal "TOP")
		(4 "In1.Cu" signal "L2GND")
		(6 "In2.Cu" signal "L3")
		(8 "In3.Cu" signal "L4VCC")
		(10 "In4.Cu" signal "L5VCC")
		(12 "In5.Cu" signal "L6")
		(14 "In6.Cu" signal "L7GND")
		(2 "B.Cu" signal "BOTTOM")
		(9 "F.Adhes" user "F.Adhesive")
		(11 "B.Adhes" user "B.Adhesive")
		(13 "F.Paste" user "Package Geometry/Pastemask Top")
		(15 "B.Paste" user "Package Geometry/Pastemask Bottom")
		(5 "F.SilkS" user "Ref Des/Silkscreen Top")
		(7 "B.SilkS" user "Ref Des/Silkscreen Bottom")
		(1 "F.Mask" user "Board Geometry/Soldermask Top")
		(3 "B.Mask" user "Board Geometry/Soldermask Bottom")
		(17 "Dwgs.User" user "User.Drawings")
		(19 "Cmts.User" user "User.Comments")
		(21 "Eco1.User" user "User.Eco1")
		(23 "Eco2.User" user "User.Eco2")
		(25 "Edge.Cuts" user "Board Geometry/Outline")
		(27 "Margin" user)
		(31 "F.CrtYd" user "Package Geometry/Place Bound Top")
		(29 "B.CrtYd" user "Package Geometry/Place Bound Bottom")
		(35 "F.Fab" user "Ref Des/Assembly Top")
		(33 "B.Fab" user "Ref Des/Assembly Bottom")
	)
	(footprint ""
		(layer "F.Cu")
		(at 40.4876 -210.4644 180)
		(property "Reference" "D30"
			(at 0 0 180)
			(layer "F.SilkS")
			(hide yes)
			(effects
				(font
					(size 1.27 1.27)
				)
			)
		)
		(property "Value" "RB551V30-1-GP"
			(at 0 -6.7818 180)
			(unlocked yes)
			(layer "F.Fab")
			(hide yes)
			(effects
				(font
					(size 1.016 1.016)
					(thickness 0.1524)
				)
			)
		)
		(property "Device Type" "SOD323AKH44"
			(at 0 -8.6868 180)
			(unlocked yes)
			(layer "F.Fab")
			(hide yes)
			(effects
				(font
					(size 1.016 1.016)
					(thickness 0.1524)
				)
			)
		)
		(duplicate_pad_numbers_are_jumpers no)
		(fp_line
			(start 0.889 2.159)
			(end -0.889 2.159)
			(stroke
				(width 0.1524)
				(type default)
			)
			(layer "F.SilkS")
		)
		(fp_line
			(start 0.889 -1.9304)
			(end 0.889 2.159)
			(stroke
				(width 0.1524)
				(type default)
			)
			(layer "F.SilkS")
		)
		(fp_line
			(start 0.762 2.0574)
			(end -0.762 2.0574)
			(stroke
				(width 0.508)
				(type default)
			)
			(layer "F.SilkS")
		)
		(fp_line
			(start -0.889 2.159)
			(end -0.889 -1.9304)
			(stroke
				(width 0.1524)
				(type default)
			)
			(layer "F.SilkS")
		)
		(fp_line
			(start -0.889 -1.9304)
			(end 0.889 -1.9304)
			(stroke
				(width 0.1524)
				(type default)
			)
			(layer "F.SilkS")
		)
		(fp_rect
			(start -1.016 2.3114)
			(end 1.016 -2.0066)
			(stroke
				(width 0)
				(type default)
			)
			(fill no)
			(layer "F.CrtYd")
		)
		(fp_poly
			(pts
				(xy -1.016 -2.0066) (xy 1.016 -2.0066) (xy 1.016 2.3114) (xy -1.016 2.3114)
			)
			(stroke
				(width 0)
				(type default)
			)
			(fill no)
			(layer "F.Fab")
		)
		(pad "A" smd rect
			(at 0 -1.143 180)
			(size 0.5588 1.016)
			(layers "F.Cu" "F.Mask" "F.Paste")
			(net "SW_SSD12_R")
		)
		(pad "K" smd rect
			(at 0 1.143 180)
			(size 0.5588 1.016)
			(layers "F.Cu" "F.Mask" "F.Paste")
			(net "SW_SSD12_N")
		)
	)
	(footprint ""
		(layer "F.Cu")
		(at 68.961 -454.66 180)
		(property "Reference" "R350"
			(at 0 0 180)
			(layer "F.SilkS")
			(hide yes)
			(effects
				(font
					(size 1.27 1.27)
				)
			)
		)
		(property "Value" "4K7R2J-2-GP"
			(at 0.064008 -3.993896 180)
			(unlocked yes)
			(layer "F.Fab")
			(hide yes)
			(effects
				(font
					(size 1.016 1.016)
					(thickness 0.1524)
				)
			)
		)
		(property "Device Type" "R402H16"
			(at 0.064008 -5.517896 180)
			(unlocked yes)
			(layer "F.Fab")
			(hide yes)
			(effects
				(font
					(size 1.016 1.016)
					(thickness 0.1524)
				)
			)
		)
		(duplicate_pad_numbers_are_jumpers no)
		(fp_line
			(start 0.508 -0.9398)
			(end -0.508 -0.9398)
			(stroke
				(width 0.1524)
				(type default)
			)
			(layer "F.SilkS")
		)
		(fp_line
			(start -0.508 -0.9398)
			(end -0.508 0.9398)
			(stroke
				(width 0.1524)
				(type default)
			)
			(layer "F.SilkS")
		)
		(fp_rect
			(start -0.508 0.9398)
			(end 0.508 -0.9398)
			(stroke
				(width 0)
				(type default)
			)
			(fill no)
			(layer "F.CrtYd")
		)
		(fp_rect
			(start -0.508 0.9398)
			(end 0.508 -0.9398)
			(stroke
				(width 0)
				(type default)
			)
			(fill no)
			(layer "F.Fab")
		)
		(pad "1" smd custom
			(at 0 -0.4445 180)
			(size 0.1397 0.1397)
			(layers "F.Cu" "F.Mask" "F.Paste")
			(net "EEPROM_A2")
			(options
				(clearance outline)
				(anchor circle)
			)
			(primitives
				(gr_poly
					(pts
						(arc
							(start -0.1778 -0.2794)
							(mid -0.249642 -0.249642)
							(end -0.2794 -0.1778)
						)
						(arc
							(start -0.2794 0.1778)
							(mid -0.249642 0.249642)
							(end -0.1778 0.2794)
						)
						(arc
							(start 0.1778 0.2794)
							(mid 0.249642 0.249642)
							(end 0.2794 0.1778)
						)
						(arc
							(start 0.2794 -0.1778)
							(mid 0.249642 -0.249642)
							(end 0.1778 -0.2794)
						)
					)
					(width 0)
					(fill yes)
				)
			)
		)
		(pad "2" smd custom
			(at 0 0.4445 180)
			(size 0.1397 0.1397)
			(layers "F.Cu" "F.Mask" "F.Paste")
			(net "GND")
			(options
				(clearance outline)
				(anchor circle)
			)
			(primitives
				(gr_poly
					(pts
						(arc
							(start -0.1778 -0.2794)
							(mid -0.249642 -0.249642)
							(end -0.2794 -0.1778)
						)
						(arc
							(start -0.2794 0.1778)
							(mid -0.249642 0.249642)
							(end -0.1778 0.2794)
						)
						(arc
							(start 0.1778 0.2794)
							(mid 0.249642 0.249642)
							(end 0.2794 0.1778)
						)
						(arc
							(start 0.2794 -0.1778)
							(mid 0.249642 -0.249642)
							(end 0.1778 -0.2794)
						)
					)
					(width 0)
					(fill yes)
				)
			)
		)
	)
	(footprint ""
		(layer "F.Cu")
		(at 221.742 -36.83 -90)
		(property "Reference" "Q49"
			(at 0 0 270)
			(layer "F.SilkS")
			(hide yes)
			(effects
				(font
					(size 1.27 1.27)
				)
			)
		)
		(property "Value" "2N7002A-7-GP"
			(at 0.127 -8.9662 270)
			(unlocked yes)
			(layer "F.Fab")
			(hide yes)
			(effects
				(font
					(size 1.016 1.016)
					(thickness 0.1524)
				)
			)
		)
		(property "Device Type" "SOT23DGS2D4H48"
			(at 0.127 -10.4902 270)
			(unlocked yes)
			(layer "F.Fab")
			(hide yes)
			(effects
				(font
					(size 1.016 1.016)
					(thickness 0.1524)
				)
			)
		)
		(duplicate_pad_numbers_are_jumpers no)
		(fp_line
			(start -1.651 1.778)
			(end 1.651 1.778)
			(stroke
				(width 0.1524)
				(type default)
			)
			(layer "F.SilkS")
		)
		(fp_line
			(start 1.651 1.778)
			(end 1.651 -1.778)
			(stroke
				(width 0.1524)
				(type default)
			)
			(layer "F.SilkS")
		)
		(fp_line
			(start -1.651 -1.778)
			(end -1.651 1.778)
			(stroke
				(width 0.1524)
				(type default)
			)
			(layer "F.SilkS")
		)
		(fp_line
			(start 1.651 -1.778)
			(end -1.651 -1.778)
			(stroke
				(width 0.1524)
				(type default)
			)
			(layer "F.SilkS")
		)
		(fp_poly
			(pts
				(xy -1.778 1.8796) (xy -1.778 -1.8796) (xy 1.778 -1.8796) (xy 1.778 1.8796)
			)
			(stroke
				(width 0)
				(type default)
			)
			(fill no)
			(layer "F.CrtYd")
		)
		(fp_poly
			(pts
				(xy -1.778 1.8796) (xy -1.778 -1.8796) (xy 1.778 -1.8796) (xy 1.778 1.8796)
			)
			(stroke
				(width 0)
				(type default)
			)
			(fill no)
			(layer "F.Fab")
		)
		(pad "D" smd custom
			(at 0 -0.9525 270)
			(size 0.1905 0.1905)
			(layers "F.Cu" "F.Mask" "F.Paste")
			(net "SSD4_CLK0_OE_MOS_N")
			(options
				(clearance outline)
				(anchor circle)
			)
			(primitives
				(gr_poly
					(pts
						(arc
							(start -0.1778 0.5715)
							(mid -0.321484 0.511984)
							(end -0.381 0.3683)
						)
						(arc
							(start -0.381 -0.3683)
							(mid -0.321484 -0.511984)
							(end -0.1778 -0.5715)
						)
						(arc
							(start 0.1778 -0.5715)
							(mid 0.321484 -0.511984)
							(end 0.381 -0.3683)
						)
						(arc
							(start 0.381 0.3683)
							(mid 0.321484 0.511984)
							(end 0.1778 0.5715)
						)
					)
					(width 0)
					(fill yes)
				)
			)
		)
		(pad "G" smd custom
			(at -0.98425 0.9525 270)
			(size 0.1905 0.1905)
			(layers "F.Cu" "F.Mask" "F.Paste")
			(net "SSD4_CLK0_OE_R_N")
			(options
				(clearance outline)
				(anchor circle)
			)
			(primitives
				(gr_poly
					(pts
						(arc
							(start -0.1778 0.5715)
							(mid -0.321484 0.511984)
							(end -0.381 0.3683)
						)
						(arc
							(start -0.381 -0.3683)
							(mid -0.321484 -0.511984)
							(end -0.1778 -0.5715)
						)
						(arc
							(start 0.1778 -0.5715)
							(mid 0.321484 -0.511984)
							(end 0.381 -0.3683)
						)
						(arc
							(start 0.381 0.3683)
							(mid 0.321484 0.511984)
							(end 0.1778 0.5715)
						)
					)
					(width 0)
					(fill yes)
				)
			)
		)
		(pad "S" smd custom
			(at 0.98425 0.9525 270)
			(size 0.1905 0.1905)
			(layers "F.Cu" "F.Mask" "F.Paste")
			(net "GND")
			(options
				(clearance outline)
				(anchor circle)
			)
			(primitives
				(gr_poly
					(pts
						(arc
							(start -0.1778 0.5715)
							(mid -0.321484 0.511984)
							(end -0.381 0.3683)
						)
						(arc
							(start -0.381 -0.3683)
							(mid -0.321484 -0.511984)
							(end -0.1778 -0.5715)
						)
						(arc
							(start 0.1778 -0.5715)
							(mid 0.321484 -0.511984)
							(end 0.381 -0.3683)
						)
						(arc
							(start 0.381 0.3683)
							(mid 0.321484 0.511984)
							(end 0.1778 0.5715)
						)
					)
					(width 0)
					(fill yes)
				)
			)
		)
	)
	(footprint ""
		(layer "F.Cu")
		(at 19.7485 -266.988544)
		(property "Reference" "SR1146"
			(at 0 0 0)
			(layer "F.SilkS")
			(hide yes)
			(effects
				(font
					(size 1.27 1.27)
				)
			)
		)
		(property "Value" "4K7R2J-2-GP"
			(at 0.064008 -3.993896 0)
			(unlocked yes)
			(layer "F.Fab")
			(hide yes)
			(effects
				(font
					(size 1.016 1.016)
					(thickness 0.1524)
				)
			)
		)
		(property "Device Type" "R402H16"
			(at 0.064008 -5.517896 0)
			(unlocked yes)
			(layer "F.Fab")
			(hide yes)
			(effects
				(font
					(size 1.016 1.016)
					(thickness 0.1524)
				)
			)
		)
		(duplicate_pad_numbers_are_jumpers no)
		(fp_line
			(start -0.508 -0.9398)
			(end -0.508 0.9398)
			(stroke
				(width 0.1524)
				(type default)
			)
			(layer "F.SilkS")
		)
		(fp_line
			(start 0.508 -0.9398)
			(end -0.508 -0.9398)
			(stroke
				(width 0.1524)
				(type default)
			)
			(layer "F.SilkS")
		)
		(fp_rect
			(start -0.508 0.9398)
			(end 0.508 -0.9398)
			(stroke
				(width 0)
				(type default)
			)
			(fill no)
			(layer "F.CrtYd")
		)
		(fp_rect
			(start -0.508 0.9398)
			(end 0.508 -0.9398)
			(stroke
				(width 0)
				(type default)
			)
			(fill no)
			(layer "F.Fab")
		)
		(pad "1" smd custom
			(at 0 -0.4445)
			(size 0.1397 0.1397)
			(layers "F.Cu" "F.Mask" "F.Paste")
			(net "P3V3")
			(options
				(clearance outline)
				(anchor circle)
			)
			(primitives
				(gr_poly
					(pts
						(arc
							(start -0.1778 -0.2794)
							(mid -0.249642 -0.249642)
							(end -0.2794 -0.1778)
						)
						(arc
							(start -0.2794 0.1778)
							(mid -0.249642 0.249642)
							(end -0.1778 0.2794)
						)
						(arc
							(start 0.1778 0.2794)
							(mid 0.249642 0.249642)
							(end 0.2794 0.1778)
						)
						(arc
							(start 0.2794 -0.1778)
							(mid 0.249642 -0.249642)
							(end 0.1778 -0.2794)
						)
					)
					(width 0)
					(fill yes)
				)
			)
		)
		(pad "2" smd custom
			(at 0 0.4445)
			(size 0.1397 0.1397)
			(layers "F.Cu" "F.Mask" "F.Paste")
			(net "SSD_ACT_DR12")
			(options
				(clearance outline)
				(anchor circle)
			)
			(primitives
				(gr_poly
					(pts
						(arc
							(start -0.1778 -0.2794)
							(mid -0.249642 -0.249642)
							(end -0.2794 -0.1778)
						)
						(arc
							(start -0.2794 0.1778)
							(mid -0.249642 0.249642)
							(end -0.1778 0.2794)
						)
						(arc
							(start 0.1778 0.2794)
							(mid 0.249642 0.249642)
							(end 0.2794 0.1778)
						)
						(arc
							(start 0.2794 -0.1778)
							(mid 0.249642 -0.249642)
							(end 0.1778 -0.2794)
						)
					)
					(width 0)
					(fill yes)
				)
			)
		)
	)
	(footprint ""
		(layer "F.Cu")
		(at 89.789 -443.865 -90)
		(property "Reference" "C9343"
			(at 0 0 270)
			(layer "F.SilkS")
			(hide yes)
			(effects
				(font
					(size 1.27 1.27)
				)
			)
		)
		(property "Value" "SC1KP50V2KX-1GP"
			(at 1.1811 -2.7051 270)
			(unlocked yes)
			(layer "F.Fab")
			(hide yes)
			(effects
				(font
					(size 1.016 1.016)
					(thickness 0.1524)
				)
			)
		)
		(property "Device Type" "C402H22"
			(at 1.1811 -4.2291 270)
			(unlocked yes)
			(layer "F.Fab")
			(hide yes)
			(effects
				(font
					(size 1.016 1.016)
					(thickness 0.1524)
				)
			)
		)
		(duplicate_pad_numbers_are_jumpers no)
		(fp_rect
			(start -0.4318 0.9525)
			(end 0.4318 -0.9525)
			(stroke
				(width 0)
				(type default)
			)
			(fill no)
			(layer "F.CrtYd")
		)
		(fp_rect
			(start -0.4318 0.9525)
			(end 0.4318 -0.9525)
			(stroke
				(width 0)
				(type default)
			)
			(fill no)
			(layer "F.Fab")
		)
		(pad "1" smd custom
			(at 0 -0.4445 270)
			(size 0.1524 0.1524)
			(layers "F.Cu" "F.Mask" "F.Paste")
			(net "SSD_PRSNT5")
			(options
				(clearance outline)
				(anchor circle)
			)
			(primitives
				(gr_poly
					(pts
						(arc
							(start 0.3048 -0.2032)
							(mid 0.275042 -0.275042)
							(end 0.2032 -0.3048)
						)
						(arc
							(start -0.2032 -0.3048)
							(mid -0.275042 -0.275042)
							(end -0.3048 -0.2032)
						)
						(arc
							(start -0.3048 0.2032)
							(mid -0.275042 0.275042)
							(end -0.2032 0.3048)
						)
						(arc
							(start 0.2032 0.3048)
							(mid 0.275042 0.275042)
							(end 0.3048 0.2032)
						)
					)
					(width 0)
					(fill yes)
				)
			)
		)
		(pad "2" smd custom
			(at 0 0.4445 270)
			(size 0.1524 0.1524)
			(layers "F.Cu" "F.Mask" "F.Paste")
			(net "GND")
			(options
				(clearance outline)
				(anchor circle)
			)
			(primitives
				(gr_poly
					(pts
						(arc
							(start 0.3048 -0.2032)
							(mid 0.275042 -0.275042)
							(end 0.2032 -0.3048)
						)
						(arc
							(start -0.2032 -0.3048)
							(mid -0.275042 -0.275042)
							(end -0.3048 -0.2032)
						)
						(arc
							(start -0.3048 0.2032)
							(mid -0.275042 0.275042)
							(end -0.2032 0.3048)
						)
						(arc
							(start 0.2032 0.3048)
							(mid 0.275042 0.275042)
							(end 0.3048 0.2032)
						)
					)
					(width 0)
					(fill yes)
				)
			)
		)
	)
	(footprint ""
		(layer "F.Cu")
		(at 82.931 -103.759 90)
		(property "Reference" "SR956"
			(at 0 0 90)
			(layer "F.SilkS")
			(hide yes)
			(effects
				(font
					(size 1.27 1.27)
				)
			)
		)
		(property "Value" "4K7R2F-GP"
			(at 0.064008 -3.993896 90)
			(unlocked yes)
			(layer "F.Fab")
			(hide yes)
			(effects
				(font
					(size 1.016 1.016)
					(thickness 0.1524)
				)
			)
		)
		(property "Device Type" "R402H16"
			(at 0.064008 -5.517896 90)
			(unlocked yes)
			(layer "F.Fab")
			(hide yes)
			(effects
				(font
					(size 1.016 1.016)
					(thickness 0.1524)
				)
			)
		)
		(duplicate_pad_numbers_are_jumpers no)
		(fp_line
			(start 0.508 -0.9398)
			(end -0.508 -0.9398)
			(stroke
				(width 0.1524)
				(type default)
			)
			(layer "F.SilkS")
		)
		(fp_line
			(start -0.508 -0.9398)
			(end -0.508 0.9398)
			(stroke
				(width 0.1524)
				(type default)
			)
			(layer "F.SilkS")
		)
		(fp_rect
			(start -0.508 0.9398)
			(end 0.508 -0.9398)
			(stroke
				(width 0)
				(type default)
			)
			(fill no)
			(layer "F.CrtYd")
		)
		(fp_rect
			(start -0.508 0.9398)
			(end 0.508 -0.9398)
			(stroke
				(width 0)
				(type default)
			)
			(fill no)
			(layer "F.Fab")
		)
		(pad "1" smd custom
			(at 0 -0.4445 90)
			(size 0.1397 0.1397)
			(layers "F.Cu" "F.Mask" "F.Paste")
			(net "VDD_DIFF_4")
			(options
				(clearance outline)
				(anchor circle)
			)
			(primitives
				(gr_poly
					(pts
						(arc
							(start -0.1778 -0.2794)
							(mid -0.249642 -0.249642)
							(end -0.2794 -0.1778)
						)
						(arc
							(start -0.2794 0.1778)
							(mid -0.249642 0.249642)
							(end -0.1778 0.2794)
						)
						(arc
							(start 0.1778 0.2794)
							(mid 0.249642 0.249642)
							(end 0.2794 0.1778)
						)
						(arc
							(start 0.2794 -0.1778)
							(mid 0.249642 -0.249642)
							(end 0.1778 -0.2794)
						)
					)
					(width 0)
					(fill yes)
				)
			)
		)
		(pad "2" smd custom
			(at 0 0.4445 90)
			(size 0.1397 0.1397)
			(layers "F.Cu" "F.Mask" "F.Paste")
			(net "P3V3_PG")
			(options
				(clearance outline)
				(anchor circle)
			)
			(primitives
				(gr_poly
					(pts
						(arc
							(start -0.1778 -0.2794)
							(mid -0.249642 -0.249642)
							(end -0.2794 -0.1778)
						)
						(arc
							(start -0.2794 0.1778)
							(mid -0.249642 0.249642)
							(end -0.1778 0.2794)
						)
						(arc
							(start 0.1778 0.2794)
							(mid 0.249642 0.249642)
							(end 0.2794 0.1778)
						)
						(arc
							(start 0.2794 -0.1778)
							(mid 0.249642 -0.249642)
							(end 0.1778 -0.2794)
						)
					)
					(width 0)
					(fill yes)
				)
			)
		)
	)
	(footprint ""
		(layer "F.Cu")
		(at 227.711 -428.752)
		(property "Reference" "PC1281"
			(at 0 0 0)
			(layer "F.SilkS")
			(hide yes)
			(effects
				(font
					(size 1.27 1.27)
				)
			)
		)
		(property "Value" "SC1U25V3KX-GP"
			(at 0 -2.8194 0)
			(unlocked yes)
			(layer "F.Fab")
			(hide yes)
			(effects
				(font
					(size 1.016 1.016)
					(thickness 0.1524)
				)
			)
		)
		(property "Device Type" "C603H36"
			(at 0 -4.3434 0)
			(unlocked yes)
			(layer "F.Fab")
			(hide yes)
			(effects
				(font
					(size 1.016 1.016)
					(thickness 0.1524)
				)
			)
		)
		(duplicate_pad_numbers_are_jumpers no)
		(fp_line
			(start 0.508 0)
			(end -0.508 0)
			(stroke
				(width 0.2032)
				(type default)
			)
			(layer "F.SilkS")
		)
		(fp_rect
			(start -0.5842 1.3335)
			(end 0.5842 -1.3335)
			(stroke
				(width 0)
				(type default)
			)
			(fill no)
			(layer "F.CrtYd")
		)
		(fp_rect
			(start -0.5842 1.3335)
			(end 0.5842 -1.3335)
			(stroke
				(width 0)
				(type default)
			)
			(fill no)
			(layer "F.Fab")
		)
		(pad "1" smd custom
			(at 0 -0.762)
			(size 0.2159 0.2159)
			(layers "F.Cu" "F.Mask" "F.Paste")
			(net "P3V3_VCC")
			(options
				(clearance outline)
				(anchor circle)
			)
			(primitives
				(gr_poly
					(pts
						(arc
							(start -0.3302 -0.4318)
							(mid -0.402042 -0.402042)
							(end -0.4318 -0.3302)
						)
						(arc
							(start -0.4318 0.3302)
							(mid -0.402042 0.402042)
							(end -0.3302 0.4318)
						)
						(arc
							(start 0.3302 0.4318)
							(mid 0.402042 0.402042)
							(end 0.4318 0.3302)
						)
						(arc
							(start 0.4318 -0.3302)
							(mid 0.402042 -0.402042)
							(end 0.3302 -0.4318)
						)
					)
					(width 0)
					(fill yes)
				)
			)
		)
		(pad "2" smd custom
			(at 0 0.762)
			(size 0.2159 0.2159)
			(layers "F.Cu" "F.Mask" "F.Paste")
			(net "AGND_P3V3")
			(options
				(clearance outline)
				(anchor circle)
			)
			(primitives
				(gr_poly
					(pts
						(arc
							(start -0.3302 -0.4318)
							(mid -0.402042 -0.402042)
							(end -0.4318 -0.3302)
						)
						(arc
							(start -0.4318 0.3302)
							(mid -0.402042 0.402042)
							(end -0.3302 0.4318)
						)
						(arc
							(start 0.3302 0.4318)
							(mid 0.402042 0.402042)
							(end 0.4318 0.3302)
						)
						(arc
							(start 0.4318 -0.3302)
							(mid 0.402042 -0.402042)
							(end 0.3302 -0.4318)
						)
					)
					(width 0)
					(fill yes)
				)
			)
		)
	)
)
